# T6G (Grand Teton) — schematic netlist excerpt (pin names and nets, part order shuffled) for the footprints in the layout excerpt that follows; sources: Cadence DE-HDL packaged netlist, KiCad conversion of 04192023_DAF0TMB3IC0_F0TG_MB_C_brd_V02_OCP.brd

PC141  Q_CAP  560PF 50V 10% EMPTY  pkg C0402  page 215 : A = SW_PVDDCR_SOC_P1_SW1 ; B = SW_PVDDCR_SOC_P1_SW1_RC
PR603  Q_RES  4.99K 1% EMPTY  pkg 0402LF  page 217 : A = PVDDCR_CPU1_P1_VINSEN ; B = GND

(kicad_pcb
	(version 20260206)
	(generator "pcbnew")
	(generator_version "10.0")
	(general
		(thickness 1.6)
		(legacy_teardrops no)
	)
	(paper "A4")
	(title_block
		(title "04192023_DAF0TMB3IC0_F0TG_MB_C_brd_V02_OCP.brd")
		(comment 1 "Grand Teton / footprints 2239-2240 of 8354")
	)
	(layers
		(0 "F.Cu" signal "TOP")
		(4 "In1.Cu" signal "GND")
		(6 "In2.Cu" signal "IN1")
		(8 "In3.Cu" signal "GND1")
		(10 "In4.Cu" signal "IN2")
		(12 "In5.Cu" signal "GND2")
		(14 "In6.Cu" signal "IN3")
		(16 "In7.Cu" signal "GND3")
		(18 "In8.Cu" signal "VCC")
		(20 "In9.Cu" signal "VCC1")
		(22 "In10.Cu" signal "GND4")
		(24 "In11.Cu" signal "IN4")
		(26 "In12.Cu" signal "GND5")
		(28 "In13.Cu" signal "IN5")
		(30 "In14.Cu" signal "GND6")
		(32 "In15.Cu" signal "IN6")
		(34 "In16.Cu" signal "GND7")
		(2 "B.Cu" signal "BOTTOM")
		(9 "F.Adhes" user "F.Adhesive")
		(11 "B.Adhes" user "B.Adhesive")
		(13 "F.Paste" user "Package Geometry/Pastemask Top")
		(15 "B.Paste" user "Package Geometry/Pastemask Bottom")
		(5 "F.SilkS" user "Ref Des/Silkscreen Top")
		(7 "B.SilkS" user "Ref Des/Silkscreen Bottom")
		(1 "F.Mask" user "Board Geometry/Soldermask Top")
		(3 "B.Mask" user "Board Geometry/Soldermask Bottom")
		(17 "Dwgs.User" user "User.Drawings")
		(19 "Cmts.User" user "User.Comments")
		(21 "Eco1.User" user "User.Eco1")
		(23 "Eco2.User" user "User.Eco2")
		(25 "Edge.Cuts" user "Board Geometry/Outline")
		(27 "Margin" user)
		(31 "F.CrtYd" user "Package Geometry/Place Bound Top")
		(29 "B.CrtYd" user "Package Geometry/Place Bound Bottom")
		(35 "F.Fab" user "Ref Des/Assembly Top")
		(33 "B.Fab" user "Ref Des/Assembly Bottom")
	)
	(footprint ""
		(layer "F.Cu")
		(at 37.338 -366.776 -90)
		(property "Reference" "PR603"
			(at 0 0 270)
			(layer "F.SilkS")
			(hide yes)
			(effects
				(font
					(size 1.27 1.27)
				)
			)
		)
		(property "Value" ""
			(at 0 0 270)
			(layer "F.Fab")
			(effects
				(font
					(size 1.27 1.27)
				)
			)
		)
		(duplicate_pad_numbers_are_jumpers no)
		(fp_line
			(start -0.7874 0.4064)
			(end -0.7874 -0.4064)
			(stroke
				(width 0.1524)
				(type default)
			)
			(layer "F.SilkS")
		)
		(fp_line
			(start 0.7874 0.4064)
			(end -0.7874 0.4064)
			(stroke
				(width 0.1524)
				(type default)
			)
			(layer "F.SilkS")
		)
		(fp_line
			(start -0.7874 -0.4064)
			(end 0.7874 -0.4064)
			(stroke
				(width 0.1524)
				(type default)
			)
			(layer "F.SilkS")
		)
		(fp_line
			(start 0.7874 -0.4064)
			(end 0.7874 0.4064)
			(stroke
				(width 0.1524)
				(type default)
			)
			(layer "F.SilkS")
		)
		(fp_line
			(start -0.67945 0.3048)
			(end -0.67945 -0.305054)
			(stroke
				(width 0.1)
				(type default)
			)
			(layer "F.Fab")
		)
		(fp_line
			(start -0.12065 0.3048)
			(end -0.67945 0.3048)
			(stroke
				(width 0.1)
				(type default)
			)
			(layer "F.Fab")
		)
		(fp_line
			(start 0.120396 0.3048)
			(end 0.120396 0.2794)
			(stroke
				(width 0.1)
				(type default)
			)
			(layer "F.Fab")
		)
		(fp_line
			(start 0.67945 0.3048)
			(end 0.120396 0.3048)
			(stroke
				(width 0.1)
				(type default)
			)
			(layer "F.Fab")
		)
		(fp_line
			(start -0.12065 0.2794)
			(end -0.12065 0.3048)
			(stroke
				(width 0.1)
				(type default)
			)
			(layer "F.Fab")
		)
		(fp_line
			(start 0.120396 0.2794)
			(end -0.12065 0.2794)
			(stroke
				(width 0.1)
				(type default)
			)
			(layer "F.Fab")
		)
		(fp_line
			(start -0.12065 -0.2794)
			(end 0.12065 -0.2794)
			(stroke
				(width 0.1)
				(type default)
			)
			(layer "F.Fab")
		)
		(fp_line
			(start 0.12065 -0.2794)
			(end 0.12065 -0.3048)
			(stroke
				(width 0.1)
				(type default)
			)
			(layer "F.Fab")
		)
		(fp_line
			(start 0.12065 -0.3048)
			(end 0.67945 -0.3048)
			(stroke
				(width 0.1)
				(type default)
			)
			(layer "F.Fab")
		)
		(fp_line
			(start 0.67945 -0.3048)
			(end 0.67945 0.3048)
			(stroke
				(width 0.1)
				(type default)
			)
			(layer "F.Fab")
		)
		(fp_line
			(start -0.67945 -0.305054)
			(end -0.12065 -0.305054)
			(stroke
				(width 0.1)
				(type default)
			)
			(layer "F.Fab")
		)
		(fp_line
			(start -0.12065 -0.305054)
			(end -0.12065 -0.2794)
			(stroke
				(width 0.1)
				(type default)
			)
			(layer "F.Fab")
		)
		(pad "1" smd circle
			(at -0.40005 0 270)
			(size 0 0)
			(layers "F.Cu" "F.Mask" "F.Paste")
			(net "PVDDCR_CPU1_P1_VINSEN")
		)
		(pad "2" smd circle
			(at 0.40005 0 270)
			(size 0 0)
			(layers "F.Cu" "F.Mask" "F.Paste")
			(net "GND")
		)
	)
	(footprint ""
		(layer "F.Cu")
		(at 119.379492 -174.927768)
		(property "Reference" "PC141"
			(at 0 0 0)
			(layer "F.SilkS")
			(hide yes)
			(effects
				(font
					(size 1.27 1.27)
				)
			)
		)
		(property "Value" ""
			(at 0 0 0)
			(layer "F.Fab")
			(effects
				(font
					(size 1.27 1.27)
				)
			)
		)
		(duplicate_pad_numbers_are_jumpers no)
		(fp_line
			(start -0.7874 -0.4064)
			(end 0.7874 -0.4064)
			(stroke
				(width 0.1524)
				(type default)
			)
			(layer "F.SilkS")
		)
		(fp_line
			(start -0.7874 0.4064)
			(end -0.7874 -0.4064)
			(stroke
				(width 0.1524)
				(type default)
			)
			(layer "F.SilkS")
		)
		(fp_line
			(start 0.7874 -0.4064)
			(end 0.7874 0.4064)
			(stroke
				(width 0.1524)
				(type default)
			)
			(layer "F.SilkS")
		)
		(fp_line
			(start 0.7874 0.4064)
			(end -0.7874 0.4064)
			(stroke
				(width 0.1524)
				(type default)
			)
			(layer "F.SilkS")
		)
		(fp_line
			(start -0.67945 -0.305054)
			(end -0.12065 -0.305054)
			(stroke
				(width 0.1)
				(type default)
			)
			(layer "F.Fab")
		)
		(fp_line
			(start -0.67945 0.3048)
			(end -0.67945 -0.305054)
			(stroke
				(width 0.1)
				(type default)
			)
			(layer "F.Fab")
		)
		(fp_line
			(start -0.12065 -0.305054)
			(end -0.12065 -0.2794)
			(stroke
				(width 0.1)
				(type default)
			)
			(layer "F.Fab")
		)
		(fp_line
			(start -0.12065 -0.2794)
			(end 0.12065 -0.2794)
			(stroke
				(width 0.1)
				(type default)
			)
			(layer "F.Fab")
		)
		(fp_line
			(start -0.12065 0.2794)
			(end -0.12065 0.3048)
			(stroke
				(width 0.1)
				(type default)
			)
			(layer "F.Fab")
		)
		(fp_line
			(start -0.12065 0.3048)
			(end -0.67945 0.3048)
			(stroke
				(width 0.1)
				(type default)
			)
			(layer "F.Fab")
		)
		(fp_line
			(start 0.120396 0.2794)
			(end -0.12065 0.2794)
			(stroke
				(width 0.1)
				(type default)
			)
			(layer "F.Fab")
		)
		(fp_line
			(start 0.120396 0.3048)
			(end 0.120396 0.2794)
			(stroke
				(width 0.1)
				(type default)
			)
			(layer "F.Fab")
		)
		(fp_line
			(start 0.12065 -0.3048)
			(end 0.67945 -0.3048)
			(stroke
				(width 0.1)
				(type default)
			)
			(layer "F.Fab")
		)
		(fp_line
			(start 0.12065 -0.2794)
			(end 0.12065 -0.3048)
			(stroke
				(width 0.1)
				(type default)
			)
			(layer "F.Fab")
		)
		(fp_line
			(start 0.67945 -0.3048)
			(end 0.67945 0.3048)
			(stroke
				(width 0.1)
				(type default)
			)
			(layer "F.Fab")
		)
		(fp_line
			(start 0.67945 0.3048)
			(end 0.120396 0.3048)
			(stroke
				(width 0.1)
				(type default)
			)
			(layer "F.Fab")
		)
		(pad "1" smd circle
			(at -0.40005 0)
			(size 0 0)
			(layers "F.Cu" "F.Mask" "F.Paste")
			(net "SW_PVDDCR_SOC_P1_SW1")
		)
		(pad "2" smd circle
			(at 0.40005 0)
			(size 0 0)
			(layers "F.Cu" "F.Mask" "F.Paste")
			(net "SW_PVDDCR_SOC_P1_SW1_RC")
		)
	)
)
